# T6G (Grand Teton) — schematic netlist excerpt (pin names and nets, part order shuffled) for the footprints in the layout excerpt that follows; sources: Cadence DE-HDL packaged netlist, KiCad conversion of 04192023_DAF0TMB3IC0_F0TG_MB_C_brd_V02_OCP.brd

C740  Q_CAP_DIFFBUS  DIFF BUS_0.22UF 6.3V 20% X6S  pkg C0201  page 66 : \1\ = P5E_CPU1_P1_TX_C_DN<0> ; \2\ = P5E_CPU1_P1_TX_DN<0>
C1991  Q_CAP_DIFFBUS  DIFF BUS_0.22UF 6.3V 20% X6S  pkg C0201  page 67 : \1\ = P3E_CPU0_P4_TX_C_DP<2> ; \2\ = P3E_CPU0_P4_TX_DP<2>
R6219  Q_RES  10K 1% CHIP  pkg 0402LF  page 176 : A = USB_CPU0_ADD_A1 ; B = GND

(kicad_pcb
	(version 20260206)
	(generator "pcbnew")
	(generator_version "10.0")
	(general
		(thickness 1.6)
		(legacy_teardrops no)
	)
	(paper "A4")
	(title_block
		(title "04192023_DAF0TMB3IC0_F0TG_MB_C_brd_V02_OCP.brd")
		(comment 1 "Grand Teton / footprints 976-978 of 8354")
	)
	(layers
		(0 "F.Cu" signal "TOP")
		(4 "In1.Cu" signal "GND")
		(6 "In2.Cu" signal "IN1")
		(8 "In3.Cu" signal "GND1")
		(10 "In4.Cu" signal "IN2")
		(12 "In5.Cu" signal "GND2")
		(14 "In6.Cu" signal "IN3")
		(16 "In7.Cu" signal "GND3")
		(18 "In8.Cu" signal "VCC")
		(20 "In9.Cu" signal "VCC1")
		(22 "In10.Cu" signal "GND4")
		(24 "In11.Cu" signal "IN4")
		(26 "In12.Cu" signal "GND5")
		(28 "In13.Cu" signal "IN5")
		(30 "In14.Cu" signal "GND6")
		(32 "In15.Cu" signal "IN6")
		(34 "In16.Cu" signal "GND7")
		(2 "B.Cu" signal "BOTTOM")
		(9 "F.Adhes" user "F.Adhesive")
		(11 "B.Adhes" user "B.Adhesive")
		(13 "F.Paste" user "Package Geometry/Pastemask Top")
		(15 "B.Paste" user "Package Geometry/Pastemask Bottom")
		(5 "F.SilkS" user "Ref Des/Silkscreen Top")
		(7 "B.SilkS" user "Ref Des/Silkscreen Bottom")
		(1 "F.Mask" user "Board Geometry/Soldermask Top")
		(3 "B.Mask" user "Board Geometry/Soldermask Bottom")
		(17 "Dwgs.User" user "User.Drawings")
		(19 "Cmts.User" user "User.Comments")
		(21 "Eco1.User" user "User.Eco1")
		(23 "Eco2.User" user "User.Eco2")
		(25 "Edge.Cuts" user "Board Geometry/Outline")
		(27 "Margin" user)
		(31 "F.CrtYd" user "Package Geometry/Place Bound Top")
		(29 "B.CrtYd" user "Package Geometry/Place Bound Bottom")
		(35 "F.Fab" user "Ref Des/Assembly Top")
		(33 "B.Fab" user "Ref Des/Assembly Bottom")
	)
	(footprint ""
		(layer "F.Cu")
		(at 105.84561 -66.58991 180)
		(property "Reference" "R6219"
			(at 0 0 180)
			(layer "F.SilkS")
			(hide yes)
			(effects
				(font
					(size 1.27 1.27)
				)
			)
		)
		(property "Value" ""
			(at 0 0 180)
			(layer "F.Fab")
			(effects
				(font
					(size 1.27 1.27)
				)
			)
		)
		(duplicate_pad_numbers_are_jumpers no)
		(fp_line
			(start 0.7874 0.4064)
			(end -0.7874 0.4064)
			(stroke
				(width 0.1524)
				(type default)
			)
			(layer "F.SilkS")
		)
		(fp_line
			(start 0.7874 -0.4064)
			(end 0.7874 0.4064)
			(stroke
				(width 0.1524)
				(type default)
			)
			(layer "F.SilkS")
		)
		(fp_line
			(start -0.7874 0.4064)
			(end -0.7874 -0.4064)
			(stroke
				(width 0.1524)
				(type default)
			)
			(layer "F.SilkS")
		)
		(fp_line
			(start -0.7874 -0.4064)
			(end 0.7874 -0.4064)
			(stroke
				(width 0.1524)
				(type default)
			)
			(layer "F.SilkS")
		)
		(fp_line
			(start 0.67945 0.3048)
			(end 0.120396 0.3048)
			(stroke
				(width 0.1)
				(type default)
			)
			(layer "F.Fab")
		)
		(fp_line
			(start 0.67945 -0.3048)
			(end 0.67945 0.3048)
			(stroke
				(width 0.1)
				(type default)
			)
			(layer "F.Fab")
		)
		(fp_line
			(start 0.12065 -0.2794)
			(end 0.12065 -0.3048)
			(stroke
				(width 0.1)
				(type default)
			)
			(layer "F.Fab")
		)
		(fp_line
			(start 0.12065 -0.3048)
			(end 0.67945 -0.3048)
			(stroke
				(width 0.1)
				(type default)
			)
			(layer "F.Fab")
		)
		(fp_line
			(start 0.120396 0.3048)
			(end 0.120396 0.2794)
			(stroke
				(width 0.1)
				(type default)
			)
			(layer "F.Fab")
		)
		(fp_line
			(start 0.120396 0.2794)
			(end -0.12065 0.2794)
			(stroke
				(width 0.1)
				(type default)
			)
			(layer "F.Fab")
		)
		(fp_line
			(start -0.12065 0.3048)
			(end -0.67945 0.3048)
			(stroke
				(width 0.1)
				(type default)
			)
			(layer "F.Fab")
		)
		(fp_line
			(start -0.12065 0.2794)
			(end -0.12065 0.3048)
			(stroke
				(width 0.1)
				(type default)
			)
			(layer "F.Fab")
		)
		(fp_line
			(start -0.12065 -0.2794)
			(end 0.12065 -0.2794)
			(stroke
				(width 0.1)
				(type default)
			)
			(layer "F.Fab")
		)
		(fp_line
			(start -0.12065 -0.305054)
			(end -0.12065 -0.2794)
			(stroke
				(width 0.1)
				(type default)
			)
			(layer "F.Fab")
		)
		(fp_line
			(start -0.67945 0.3048)
			(end -0.67945 -0.305054)
			(stroke
				(width 0.1)
				(type default)
			)
			(layer "F.Fab")
		)
		(fp_line
			(start -0.67945 -0.305054)
			(end -0.12065 -0.305054)
			(stroke
				(width 0.1)
				(type default)
			)
			(layer "F.Fab")
		)
		(pad "1" smd circle
			(at -0.40005 0 180)
			(size 0 0)
			(layers "F.Cu" "F.Mask" "F.Paste")
			(net "USB_CPU0_ADD_A1")
		)
		(pad "2" smd circle
			(at 0.40005 0 180)
			(size 0 0)
			(layers "F.Cu" "F.Mask" "F.Paste")
			(net "GND")
		)
	)
	(footprint ""
		(layer "F.Cu")
		(at 240.854484 -55.612792)
		(property "Reference" "C1991"
			(at 0 0 0)
			(layer "F.SilkS")
			(hide yes)
			(effects
				(font
					(size 1.27 1.27)
				)
			)
		)
		(property "Value" ""
			(at 0 0 0)
			(layer "F.Fab")
			(effects
				(font
					(size 1.27 1.27)
				)
			)
		)
		(duplicate_pad_numbers_are_jumpers no)
		(fp_line
			(start -0.299974 -0.150114)
			(end 0.299974 -0.150114)
			(stroke
				(width 0.1)
				(type default)
			)
			(layer "F.Fab")
		)
		(fp_line
			(start -0.299974 0.150114)
			(end -0.299974 -0.150114)
			(stroke
				(width 0.1)
				(type default)
			)
			(layer "F.Fab")
		)
		(fp_line
			(start 0.299974 -0.150114)
			(end 0.299974 0.150114)
			(stroke
				(width 0.1)
				(type default)
			)
			(layer "F.Fab")
		)
		(fp_line
			(start 0.299974 0.150114)
			(end -0.299974 0.150114)
			(stroke
				(width 0.1)
				(type default)
			)
			(layer "F.Fab")
		)
		(pad "1" smd rect
			(at -0.2667 0)
			(size 0.3048 0.381)
			(layers "F.Cu" "F.Mask" "F.Paste")
			(net "P3E_CPU0_P4_TX_C_DP<2>")
		)
		(pad "2" smd rect
			(at 0.2667 0)
			(size 0.3048 0.381)
			(layers "F.Cu" "F.Mask" "F.Paste")
			(net "P3E_CPU0_P4_TX_DP<2>")
		)
	)
	(footprint ""
		(layer "F.Cu")
		(at 75.49515 -381.48006 180)
		(property "Reference" "C740"
			(at 0 0 180)
			(layer "F.SilkS")
			(hide yes)
			(effects
				(font
					(size 1.27 1.27)
				)
			)
		)
		(property "Value" ""
			(at 0 0 180)
			(layer "F.Fab")
			(effects
				(font
					(size 1.27 1.27)
				)
			)
		)
		(duplicate_pad_numbers_are_jumpers no)
		(fp_line
			(start 0.299974 0.150114)
			(end -0.299974 0.150114)
			(stroke
				(width 0.1)
				(type default)
			)
			(layer "F.Fab")
		)
		(fp_line
			(start 0.299974 -0.150114)
			(end 0.299974 0.150114)
			(stroke
				(width 0.1)
				(type default)
			)
			(layer "F.Fab")
		)
		(fp_line
			(start -0.299974 0.150114)
			(end -0.299974 -0.150114)
			(stroke
				(width 0.1)
				(type default)
			)
			(layer "F.Fab")
		)
		(fp_line
			(start -0.299974 -0.150114)
			(end 0.299974 -0.150114)
			(stroke
				(width 0.1)
				(type default)
			)
			(layer "F.Fab")
		)
		(pad "1" smd rect
			(at -0.2667 0 180)
			(size 0.3048 0.381)
			(layers "F.Cu" "F.Mask" "F.Paste")
			(net "P5E_CPU1_P1_TX_C_DN<0>")
		)
		(pad "2" smd rect
			(at 0.2667 0 180)
			(size 0.3048 0.381)
			(layers "F.Cu" "F.Mask" "F.Paste")
			(net "P5E_CPU1_P1_TX_DN<0>")
		)
	)
)
